(kicad_pcb
	(version 20260206)
	(generator "pcbnew")
	(generator_version "10.0")
	(general
		(thickness 1.6)
		(legacy_teardrops no)
	)
	(paper "A4")
	(title_block
		(title "fcb — Lightning_FCB_BRD.brd")
		(comment 1 "Lightning (Wiwynn / Facebook NVMe JBOF) / footprint 218 of 495 (CN10), pads 1-56 of 56")
	)
	(layers
		(0 "F.Cu" signal "TOP")
		(4 "In1.Cu" signal "L2GND")
		(6 "In2.Cu" signal "L3VCC")
		(2 "B.Cu" signal "BOTTOM")
		(9 "F.Adhes" user "F.Adhesive")
		(11 "B.Adhes" user "B.Adhesive")
		(13 "F.Paste" user "Package Geometry/Pastemask Top")
		(15 "B.Paste" user "Package Geometry/Pastemask Bottom")
		(5 "F.SilkS" user "Ref Des/Silkscreen Top")
		(7 "B.SilkS" user "Ref Des/Silkscreen Bottom")
		(1 "F.Mask" user "Board Geometry/Soldermask Top")
		(3 "B.Mask" user "Board Geometry/Soldermask Bottom")
		(17 "Dwgs.User" user "User.Drawings")
		(19 "Cmts.User" user "User.Comments")
		(21 "Eco1.User" user "User.Eco1")
		(23 "Eco2.User" user "User.Eco2")
		(25 "Edge.Cuts" user "Board Geometry/Outline")
		(27 "Margin" user)
		(31 "F.CrtYd" user "Package Geometry/Place Bound Top")
		(29 "B.CrtYd" user "Package Geometry/Place Bound Bottom")
		(35 "F.Fab" user "Ref Des/Assembly Top")
		(33 "B.Fab" user "Ref Des/Assembly Bottom")
	)
	(footprint ""
		(layer "F.Cu")
		(at 37.999924 -56.999886 -90)
		(property "Reference" "CN10"
			(at 0 0 270)
			(layer "F.SilkS")
			(hide yes)
			(effects
				(font
					(size 1.27 1.27)
				)
			)
		)
		(property "Value" "FCI-CONN52-4R-1-GP"
			(at -30.89656 -6.096 270)
			(unlocked yes)
			(layer "F.Fab")
			(hide yes)
			(effects
				(font
					(size 1.016 1.016)
					(thickness 0.1524)
				)
			)
		)
		(property "Device Type" "51952-220LF"
			(at -30.89656 -7.62 270)
			(unlocked yes)
			(layer "F.Fab")
			(hide yes)
			(effects
				(font
					(size 1.016 1.016)
					(thickness 0.1524)
				)
			)
		)
		(duplicate_pad_numbers_are_jumpers no)
		(pad "" np_thru_hole circle
			(at -26.67 0 270)
			(size 0.254 0.254)
			(drill 3.2004)
			(layers "*.Cu" "*.Mask")
			(clearance 1.8288)
			(thermal_gap 1.8288)
		)
		(pad "" np_thru_hole circle
			(at -21.59 0 270)
			(size 0.254 0.254)
			(drill 2.5146)
			(layers "*.Cu" "*.Mask")
			(clearance 1.4859)
			(thermal_gap 1.4859)
		)
		(pad "" np_thru_hole circle
			(at 21.59 0 270)
			(size 0.254 0.254)
			(drill 2.5146)
			(layers "*.Cu" "*.Mask")
			(clearance 1.4859)
			(thermal_gap 1.4859)
		)
		(pad "" np_thru_hole circle
			(at 26.67 0 270)
			(size 0.254 0.254)
			(drill 3.2004)
			(layers "*.Cu" "*.Mask")
			(clearance 1.8288)
			(thermal_gap 1.8288)
		)
		(pad "A1" thru_hole circle
			(at -5.08 0 270)
			(size 1.4478 1.4478)
			(drill 1.0414)
			(layers "*.Cu" "*.Mask")
			(remove_unused_layers no)
			(net "I2C_C_SDA_CONN_R")
			(clearance 0.1524)
			(thermal_gap 0.1524)
		)
		(pad "A2" thru_hole circle
			(at -2.54 0 270)
			(size 1.4478 1.4478)
			(drill 1.0414)
			(layers "*.Cu" "*.Mask")
			(remove_unused_layers no)
			(net "GND")
			(clearance 0.1524)
			(thermal_gap 0.1524)
		)
		(pad "A3" thru_hole circle
			(at 0 0 270)
			(size 1.4478 1.4478)
			(drill 1.0414)
			(layers "*.Cu" "*.Mask")
			(remove_unused_layers no)
			(net "I2C_C_SCL_CONN_R")
			(clearance 0.1524)
			(thermal_gap 0.1524)
		)
		(pad "A4" thru_hole circle
			(at 2.54 0 270)
			(size 1.4478 1.4478)
			(drill 1.0414)
			(layers "*.Cu" "*.Mask")
			(remove_unused_layers no)
			(net "GND")
			(clearance 0.1524)
			(thermal_gap 0.1524)
		)
		(pad "A5" thru_hole circle
			(at 5.08 0 270)
			(size 1.4478 1.4478)
			(drill 1.0414)
			(layers "*.Cu" "*.Mask")
			(remove_unused_layers no)
			(net "PWM_EXP_2B")
			(clearance 0.1524)
			(thermal_gap 0.1524)
		)
		(pad "B1" thru_hole circle
			(at -5.08 -2.54 270)
			(size 1.4478 1.4478)
			(drill 1.0414)
			(layers "*.Cu" "*.Mask")
			(remove_unused_layers no)
			(net "GND")
			(clearance 0.1524)
			(thermal_gap 0.1524)
		)
		(pad "B2" thru_hole circle
			(at -2.54 -2.54 270)
			(size 1.4478 1.4478)
			(drill 1.0414)
			(layers "*.Cu" "*.Mask")
			(remove_unused_layers no)
			(net "PWM_EXP_2A")
			(clearance 0.1524)
			(thermal_gap 0.1524)
		)
		(pad "B3" thru_hole circle
			(at 0 -2.54 270)
			(size 1.4478 1.4478)
			(drill 1.0414)
			(layers "*.Cu" "*.Mask")
			(remove_unused_layers no)
			(net "GND")
			(clearance 0.1524)
			(thermal_gap 0.1524)
		)
		(pad "B4" thru_hole circle
			(at 2.54 -2.54 270)
			(size 1.4478 1.4478)
			(drill 1.0414)
			(layers "*.Cu" "*.Mask")
			(remove_unused_layers no)
			(net "SELF_2B_HB")
			(clearance 0.1524)
			(thermal_gap 0.1524)
		)
		(pad "B5" thru_hole circle
			(at 5.08 -2.54 270)
			(size 1.4478 1.4478)
			(drill 1.0414)
			(layers "*.Cu" "*.Mask")
			(remove_unused_layers no)
			(net "GND")
			(clearance 0.1524)
			(thermal_gap 0.1524)
		)
		(pad "C1" thru_hole circle
			(at -5.08 -5.08 270)
			(size 1.4478 1.4478)
			(drill 1.0414)
			(layers "*.Cu" "*.Mask")
			(remove_unused_layers no)
			(net "P12VL_2490_EN_1")
			(clearance 0.1524)
			(thermal_gap 0.1524)
		)
		(pad "C2" thru_hole circle
			(at -2.54 -5.08 270)
			(size 1.4478 1.4478)
			(drill 1.0414)
			(layers "*.Cu" "*.Mask")
			(remove_unused_layers no)
			(net "P12VL_2490_EN_2")
			(clearance 0.1524)
			(thermal_gap 0.1524)
		)
		(pad "C3" thru_hole circle
			(at 0 -5.08 270)
			(size 1.4478 1.4478)
			(drill 1.0414)
			(layers "*.Cu" "*.Mask")
			(remove_unused_layers no)
			(net "SELF_2A_HB")
			(clearance 0.1524)
			(thermal_gap 0.1524)
		)
		(pad "C4" thru_hole circle
			(at 2.54 -5.08 270)
			(size 1.4478 1.4478)
			(drill 1.0414)
			(layers "*.Cu" "*.Mask")
			(remove_unused_layers no)
			(net "SEB_PEER_2A_HB")
			(clearance 0.1524)
			(thermal_gap 0.1524)
		)
		(pad "C5" thru_hole circle
			(at 5.08 -5.08 270)
			(size 1.4478 1.4478)
			(drill 1.0414)
			(layers "*.Cu" "*.Mask")
			(remove_unused_layers no)
			(net "SEB_PEER_2B_HB")
			(clearance 0.1524)
			(thermal_gap 0.1524)
		)
		(pad "D1" thru_hole circle
			(at -5.08 -7.62 270)
			(size 1.4478 1.4478)
			(drill 1.0414)
			(layers "*.Cu" "*.Mask")
			(remove_unused_layers no)
			(net "PEER_TRAY PRESENT_LOWER")
			(clearance 0.1524)
			(thermal_gap 0.1524)
		)
		(pad "D2" thru_hole circle
			(at -2.54 -7.62 270)
			(size 1.4478 1.4478)
			(drill 1.0414)
			(layers "*.Cu" "*.Mask")
			(remove_unused_layers no)
			(net "LOWER_TRAY_ID")
			(clearance 0.1524)
			(thermal_gap 0.1524)
		)
		(pad "D3" thru_hole circle
			(at 0 -7.62 270)
			(size 1.4478 1.4478)
			(drill 1.0414)
			(layers "*.Cu" "*.Mask")
			(remove_unused_layers no)
			(net "FCB_HW_REVISION")
			(clearance 0.1524)
			(thermal_gap 0.1524)
		)
		(pad "D4" thru_hole circle
			(at 2.54 -7.62 270)
			(size 1.4478 1.4478)
			(drill 1.0414)
			(layers "*.Cu" "*.Mask")
			(remove_unused_layers no)
			(net "SD_LATCH_RELEASE_L")
			(clearance 0.1524)
			(thermal_gap 0.1524)
		)
		(pad "D5" thru_hole circle
			(at 5.08 -7.62 270)
			(size 1.4478 1.4478)
			(drill 1.0414)
			(layers "*.Cu" "*.Mask")
			(remove_unused_layers no)
			(net "SELF_TRAY_PRESENT_LOWER")
			(clearance 0.1524)
			(thermal_gap 0.1524)
		)
		(pad "P1_1" thru_hole circle
			(at -15.88008 0 270)
			(size 1.4478 1.4478)
			(drill 1.0414)
			(layers "*.Cu" "*.Mask")
			(remove_unused_layers no)
			(net "P12VL")
			(clearance 0.1524)
			(thermal_gap 0.1524)
		)
		(pad "P1_2" thru_hole circle
			(at -15.88008 -2.54 270)
			(size 1.4478 1.4478)
			(drill 1.0414)
			(layers "*.Cu" "*.Mask")
			(remove_unused_layers no)
			(net "P12VL")
			(clearance 0.1524)
			(thermal_gap 0.1524)
		)
		(pad "P1_3" thru_hole circle
			(at -15.88008 -5.08 270)
			(size 1.4478 1.4478)
			(drill 1.0414)
			(layers "*.Cu" "*.Mask")
			(remove_unused_layers no)
			(net "P12VL")
			(clearance 0.1524)
			(thermal_gap 0.1524)
		)
		(pad "P1_4" thru_hole circle
			(at -15.88008 -7.62 270)
			(size 1.4478 1.4478)
			(drill 1.0414)
			(layers "*.Cu" "*.Mask")
			(remove_unused_layers no)
			(net "P12VL")
			(clearance 0.1524)
			(thermal_gap 0.1524)
		)
		(pad "P1_5" thru_hole circle
			(at -13.34008 0 270)
			(size 1.4478 1.4478)
			(drill 1.0414)
			(layers "*.Cu" "*.Mask")
			(remove_unused_layers no)
			(net "P12VL")
			(clearance 0.1524)
			(thermal_gap 0.1524)
		)
		(pad "P1_6" thru_hole circle
			(at -13.34008 -2.54 270)
			(size 1.4478 1.4478)
			(drill 1.0414)
			(layers "*.Cu" "*.Mask")
			(remove_unused_layers no)
			(net "P12VL")
			(clearance 0.1524)
			(thermal_gap 0.1524)
		)
		(pad "P1_7" thru_hole circle
			(at -13.34008 -5.08 270)
			(size 1.4478 1.4478)
			(drill 1.0414)
			(layers "*.Cu" "*.Mask")
			(remove_unused_layers no)
			(net "P12VL")
			(clearance 0.1524)
			(thermal_gap 0.1524)
		)
		(pad "P1_8" thru_hole circle
			(at -13.34008 -7.62 270)
			(size 1.4478 1.4478)
			(drill 1.0414)
			(layers "*.Cu" "*.Mask")
			(remove_unused_layers no)
			(net "P12VL")
			(clearance 0.1524)
			(thermal_gap 0.1524)
		)
		(pad "P2_1" thru_hole circle
			(at -10.80008 0 270)
			(size 1.4478 1.4478)
			(drill 1.0414)
			(layers "*.Cu" "*.Mask")
			(remove_unused_layers no)
			(net "P12VL")
			(clearance 0.1524)
			(thermal_gap 0.1524)
		)
		(pad "P2_2" thru_hole circle
			(at -10.80008 -2.54 270)
			(size 1.4478 1.4478)
			(drill 1.0414)
			(layers "*.Cu" "*.Mask")
			(remove_unused_layers no)
			(net "P12VL")
			(clearance 0.1524)
			(thermal_gap 0.1524)
		)
		(pad "P2_3" thru_hole circle
			(at -10.80008 -5.08 270)
			(size 1.4478 1.4478)
			(drill 1.0414)
			(layers "*.Cu" "*.Mask")
			(remove_unused_layers no)
			(net "P12VL")
			(clearance 0.1524)
			(thermal_gap 0.1524)
		)
		(pad "P2_4" thru_hole circle
			(at -10.80008 -7.62 270)
			(size 1.4478 1.4478)
			(drill 1.0414)
			(layers "*.Cu" "*.Mask")
			(remove_unused_layers no)
			(net "P12VL")
			(clearance 0.1524)
			(thermal_gap 0.1524)
		)
		(pad "P2_5" thru_hole circle
			(at -8.26008 0 270)
			(size 1.4478 1.4478)
			(drill 1.0414)
			(layers "*.Cu" "*.Mask")
			(remove_unused_layers no)
			(net "P12VL")
			(clearance 0.1524)
			(thermal_gap 0.1524)
		)
		(pad "P2_6" thru_hole circle
			(at -8.26008 -2.54 270)
			(size 1.4478 1.4478)
			(drill 1.0414)
			(layers "*.Cu" "*.Mask")
			(remove_unused_layers no)
			(net "P12VL")
			(clearance 0.1524)
			(thermal_gap 0.1524)
		)
		(pad "P2_7" thru_hole circle
			(at -8.26008 -5.08 270)
			(size 1.4478 1.4478)
			(drill 1.0414)
			(layers "*.Cu" "*.Mask")
			(remove_unused_layers no)
			(net "P12VL")
			(clearance 0.1524)
			(thermal_gap 0.1524)
		)
		(pad "P2_8" thru_hole circle
			(at -8.26008 -7.62 270)
			(size 1.4478 1.4478)
			(drill 1.0414)
			(layers "*.Cu" "*.Mask")
			(remove_unused_layers no)
			(net "P12VL")
			(clearance 0.1524)
			(thermal_gap 0.1524)
		)
		(pad "P3_1" thru_hole circle
			(at 8.26008 0 270)
			(size 1.4478 1.4478)
			(drill 1.0414)
			(layers "*.Cu" "*.Mask")
			(remove_unused_layers no)
			(net "GND")
			(clearance 0.1524)
			(thermal_gap 0.1524)
		)
		(pad "P3_2" thru_hole circle
			(at 8.26008 -2.54 270)
			(size 1.4478 1.4478)
			(drill 1.0414)
			(layers "*.Cu" "*.Mask")
			(remove_unused_layers no)
			(net "GND")
			(clearance 0.1524)
			(thermal_gap 0.1524)
		)
		(pad "P3_3" thru_hole circle
			(at 8.26008 -5.08 270)
			(size 1.4478 1.4478)
			(drill 1.0414)
			(layers "*.Cu" "*.Mask")
			(remove_unused_layers no)
			(net "GND")
			(clearance 0.1524)
			(thermal_gap 0.1524)
		)
		(pad "P3_4" thru_hole circle
			(at 8.26008 -7.62 270)
			(size 1.4478 1.4478)
			(drill 1.0414)
			(layers "*.Cu" "*.Mask")
			(remove_unused_layers no)
			(net "GND")
			(clearance 0.1524)
			(thermal_gap 0.1524)
		)
		(pad "P3_5" thru_hole circle
			(at 10.80008 0 270)
			(size 1.4478 1.4478)
			(drill 1.0414)
			(layers "*.Cu" "*.Mask")
			(remove_unused_layers no)
			(net "GND")
			(clearance 0.1524)
			(thermal_gap 0.1524)
		)
		(pad "P3_6" thru_hole circle
			(at 10.80008 -2.54 270)
			(size 1.4478 1.4478)
			(drill 1.0414)
			(layers "*.Cu" "*.Mask")
			(remove_unused_layers no)
			(net "GND")
			(clearance 0.1524)
			(thermal_gap 0.1524)
		)
		(pad "P3_7" thru_hole circle
			(at 10.80008 -5.08 270)
			(size 1.4478 1.4478)
			(drill 1.0414)
			(layers "*.Cu" "*.Mask")
			(remove_unused_layers no)
			(net "GND")
			(clearance 0.1524)
			(thermal_gap 0.1524)
		)
		(pad "P3_8" thru_hole circle
			(at 10.80008 -7.62 270)
			(size 1.4478 1.4478)
			(drill 1.0414)
			(layers "*.Cu" "*.Mask")
			(remove_unused_layers no)
			(net "GND")
			(clearance 0.1524)
			(thermal_gap 0.1524)
		)
		(pad "P4_1" thru_hole circle
			(at 13.34008 0 270)
			(size 1.4478 1.4478)
			(drill 1.0414)
			(layers "*.Cu" "*.Mask")
			(remove_unused_layers no)
			(net "GND")
			(clearance 0.1524)
			(thermal_gap 0.1524)
		)
		(pad "P4_2" thru_hole circle
			(at 13.34008 -2.54 270)
			(size 1.4478 1.4478)
			(drill 1.0414)
			(layers "*.Cu" "*.Mask")
			(remove_unused_layers no)
			(net "GND")
			(clearance 0.1524)
			(thermal_gap 0.1524)
		)
		(pad "P4_3" thru_hole circle
			(at 13.34008 -5.08 270)
			(size 1.4478 1.4478)
			(drill 1.0414)
			(layers "*.Cu" "*.Mask")
			(remove_unused_layers no)
			(net "GND")
			(clearance 0.1524)
			(thermal_gap 0.1524)
		)
		(pad "P4_4" thru_hole circle
			(at 13.34008 -7.62 270)
			(size 1.4478 1.4478)
			(drill 1.0414)
			(layers "*.Cu" "*.Mask")
			(remove_unused_layers no)
			(net "GND")
			(clearance 0.1524)
			(thermal_gap 0.1524)
		)
		(pad "P4_5" thru_hole circle
			(at 15.88008 0 270)
			(size 1.4478 1.4478)
			(drill 1.0414)
			(layers "*.Cu" "*.Mask")
			(remove_unused_layers no)
			(net "GND")
			(clearance 0.1524)
			(thermal_gap 0.1524)
		)
		(pad "P4_6" thru_hole circle
			(at 15.88008 -2.54 270)
			(size 1.4478 1.4478)
			(drill 1.0414)
			(layers "*.Cu" "*.Mask")
			(remove_unused_layers no)
			(net "GND")
			(clearance 0.1524)
			(thermal_gap 0.1524)
		)
		(pad "P4_7" thru_hole circle
			(at 15.88008 -5.08 270)
			(size 1.4478 1.4478)
			(drill 1.0414)
			(layers "*.Cu" "*.Mask")
			(remove_unused_layers no)
			(net "GND")
			(clearance 0.1524)
			(thermal_gap 0.1524)
		)
		(pad "P4_8" thru_hole circle
			(at 15.88008 -7.62 270)
			(size 1.4478 1.4478)
			(drill 1.0414)
			(layers "*.Cu" "*.Mask")
			(remove_unused_layers no)
			(net "GND")
			(clearance 0.1524)
			(thermal_gap 0.1524)
		)
	)
)
